# BASEBOARD_FAB2 (Tioga Pass) — schematic netlist excerpt (pin names and nets, part order shuffled) for the footprints in the layout excerpt that follows; sources: Cadence DE-HDL packaged netlist, KiCad conversion of Wiwynn_Tioga_Pass_MB.brd

R1U8  RES  0.0 5% CHIP  pkg 0402  page 159 : A = SMB_VR_STBY_LVC3_SDA_R ; B = SMB_VR_STBY_LVC3_SDA
R1B8  RES  150.0 1% CHIP  pkg 0402  page 226 : A = SVID_CLK1_CPU1_R ; B = SVID_CLK_PVDDQ_KLM
C4A15  CAP  10UF 4V 20% X6S  pkg 0603LF  page 230 : A = PVDDQ_KLM ; B = GND

(kicad_pcb
	(version 20260206)
	(generator "pcbnew")
	(generator_version "10.0")
	(general
		(thickness 1.6)
		(legacy_teardrops no)
	)
	(paper "A4")
	(title_block
		(title "Wiwynn_Tioga_Pass_MB.brd")
		(comment 1 "Tioga Pass / footprints 1816-1818 of 4770")
	)
	(layers
		(0 "F.Cu" signal "TOP")
		(4 "In1.Cu" signal "L2GND")
		(6 "In2.Cu" signal "L3")
		(8 "In3.Cu" signal "L4GND")
		(10 "In4.Cu" signal "L5")
		(12 "In5.Cu" signal "L6GND")
		(14 "In6.Cu" signal "L7VCC")
		(16 "In7.Cu" signal "L8VCC")
		(18 "In8.Cu" signal "L9GND")
		(20 "In9.Cu" signal "L10")
		(22 "In10.Cu" signal "L11GND")
		(24 "In11.Cu" signal "L12")
		(26 "In12.Cu" signal "L13GND")
		(2 "B.Cu" signal "BOTTOM")
		(9 "F.Adhes" user "F.Adhesive")
		(11 "B.Adhes" user "B.Adhesive")
		(13 "F.Paste" user "Package Geometry/Pastemask Top")
		(15 "B.Paste" user "Package Geometry/Pastemask Bottom")
		(5 "F.SilkS" user "Ref Des/Silkscreen Top")
		(7 "B.SilkS" user "Ref Des/Silkscreen Bottom")
		(1 "F.Mask" user "Board Geometry/Soldermask Top")
		(3 "B.Mask" user "Board Geometry/Soldermask Bottom")
		(17 "Dwgs.User" user "User.Drawings")
		(19 "Cmts.User" user "User.Comments")
		(21 "Eco1.User" user "User.Eco1")
		(23 "Eco2.User" user "User.Eco2")
		(25 "Edge.Cuts" user "Board Geometry/Outline")
		(27 "Margin" user)
		(31 "F.CrtYd" user "Package Geometry/Place Bound Top")
		(29 "B.CrtYd" user "Package Geometry/Place Bound Bottom")
		(35 "F.Fab" user "Ref Des/Assembly Top")
		(33 "B.Fab" user "Ref Des/Assembly Bottom")
	)
	(footprint ""
		(layer "F.Cu")
		(at 168.9608 -144.6276 90)
		(property "Reference" "C4A15"
			(at 0 0 90)
			(layer "F.SilkS")
			(hide yes)
			(effects
				(font
					(size 1.27 1.27)
				)
			)
		)
		(property "Value" ""
			(at 0 0 90)
			(layer "F.Fab")
			(effects
				(font
					(size 1.27 1.27)
				)
			)
		)
		(duplicate_pad_numbers_are_jumpers no)
		(fp_rect
			(start 0.4953 1.6002)
			(end -0.4953 -0.2032)
			(stroke
				(width 0)
				(type default)
			)
			(fill no)
			(layer "F.CrtYd")
		)
		(fp_line
			(start 0.4953 -0.2032)
			(end 0.4953 1.6002)
			(stroke
				(width 0.1)
				(type default)
			)
			(layer "F.Fab")
		)
		(fp_line
			(start -0.4953 -0.2032)
			(end 0.4953 -0.2032)
			(stroke
				(width 0.1)
				(type default)
			)
			(layer "F.Fab")
		)
		(fp_line
			(start 0.4953 1.6002)
			(end -0.4953 1.6002)
			(stroke
				(width 0.1)
				(type default)
			)
			(layer "F.Fab")
		)
		(fp_line
			(start -0.4953 1.6002)
			(end -0.4953 -0.2032)
			(stroke
				(width 0.1)
				(type default)
			)
			(layer "F.Fab")
		)
		(pad "1" smd rect
			(at 0 0 90)
			(size 0.762 0.889)
			(layers "F.Cu" "F.Mask" "F.Paste")
			(net "PVDDQ_KLM")
		)
		(pad "2" smd rect
			(at 0 1.397 90)
			(size 0.762 0.889)
			(layers "F.Cu" "F.Mask" "F.Paste")
			(net "GND")
		)
		(zone
			(layer "F.Cu")
			(hatch none 0.5)
			(connect_pads
				(clearance 0)
			)
			(min_thickness 0.25)
			(keepout
				(tracks not_allowed)
				(vias allowed)
				(pads allowed)
				(copperpour not_allowed)
				(footprints allowed)
			)
			(placement
				(enabled no)
				(sheetname "")
			)
			(fill
				(thermal_gap 0.5)
				(thermal_bridge_width 0.5)
				(island_removal_mode 0)
			)
			(polygon
				(pts
					(xy 169.9133 -145.0086) (xy 169.4053 -145.0086) (xy 169.4053 -144.2466) (xy 169.9133 -144.2466)
				)
			)
		)
	)
	(footprint ""
		(layer "F.Cu")
		(at 418.465 -18.7452)
		(property "Reference" "R1U8"
			(at 0 0 0)
			(layer "F.SilkS")
			(hide yes)
			(effects
				(font
					(size 1.27 1.27)
				)
			)
		)
		(property "Value" ""
			(at 0 0 0)
			(layer "F.Fab")
			(effects
				(font
					(size 1.27 1.27)
				)
			)
		)
		(duplicate_pad_numbers_are_jumpers no)
		(fp_poly
			(pts
				(xy -0.2794 -0.1016) (xy 0.2794 -0.1016) (xy 0.2794 0.9906) (xy -0.2794 0.9906)
			)
			(stroke
				(width 0)
				(type default)
			)
			(fill no)
			(layer "F.CrtYd")
		)
		(fp_line
			(start -0.2794 -0.1016)
			(end -0.2794 0.9906)
			(stroke
				(width 0.1)
				(type default)
			)
			(layer "F.Fab")
		)
		(fp_line
			(start -0.2794 0.9906)
			(end 0.2794 0.9906)
			(stroke
				(width 0.1)
				(type default)
			)
			(layer "F.Fab")
		)
		(fp_line
			(start 0.2794 -0.1016)
			(end -0.2794 -0.1016)
			(stroke
				(width 0.1)
				(type default)
			)
			(layer "F.Fab")
		)
		(fp_line
			(start 0.2794 0.9906)
			(end 0.2794 -0.1016)
			(stroke
				(width 0.1)
				(type default)
			)
			(layer "F.Fab")
		)
		(pad "1" smd rect
			(at 0 0)
			(size 0.508 0.508)
			(layers "F.Cu" "F.Mask" "F.Paste")
			(net "SMB_VR_STBY_LVC3_SDA_R")
		)
		(pad "2" smd rect
			(at 0 0.889)
			(size 0.508 0.508)
			(layers "F.Cu" "F.Mask" "F.Paste")
			(net "SMB_VR_STBY_LVC3_SDA")
		)
		(zone
			(layer "F.Cu")
			(hatch none 0.5)
			(connect_pads
				(clearance 0)
			)
			(min_thickness 0.25)
			(keepout
				(tracks allowed)
				(vias not_allowed)
				(pads allowed)
				(copperpour not_allowed)
				(footprints allowed)
			)
			(placement
				(enabled no)
				(sheetname "")
			)
			(fill
				(thermal_gap 0.5)
				(thermal_bridge_width 0.5)
				(island_removal_mode 0)
			)
			(polygon
				(pts
					(xy 418.211 -18.4912) (xy 418.719 -18.4912) (xy 418.719 -18.1102) (xy 418.211 -18.1102)
				)
			)
		)
		(zone
			(layer "F.Cu")
			(hatch none 0.5)
			(connect_pads
				(clearance 0)
			)
			(min_thickness 0.25)
			(keepout
				(tracks not_allowed)
				(vias allowed)
				(pads allowed)
				(copperpour not_allowed)
				(footprints allowed)
			)
			(placement
				(enabled no)
				(sheetname "")
			)
			(fill
				(thermal_gap 0.5)
				(thermal_bridge_width 0.5)
				(island_removal_mode 0)
			)
			(polygon
				(pts
					(xy 418.211 -18.1102) (xy 418.719 -18.1102) (xy 418.719 -18.4912) (xy 418.211 -18.4912)
				)
			)
		)
	)
	(footprint ""
		(layer "F.Cu")
		(at -3.556 -128.6002 90)
		(property "Reference" "R1B8"
			(at 0 0 90)
			(layer "F.SilkS")
			(hide yes)
			(effects
				(font
					(size 1.27 1.27)
				)
			)
		)
		(property "Value" ""
			(at 0 0 90)
			(layer "F.Fab")
			(effects
				(font
					(size 1.27 1.27)
				)
			)
		)
		(duplicate_pad_numbers_are_jumpers no)
		(fp_rect
			(start -0.2794 -0.1016)
			(end 0.2794 0.9906)
			(stroke
				(width 0)
				(type default)
			)
			(fill no)
			(layer "F.CrtYd")
		)
		(fp_line
			(start 0.2794 -0.1016)
			(end -0.2794 -0.1016)
			(stroke
				(width 0.1)
				(type default)
			)
			(layer "F.Fab")
		)
		(fp_line
			(start -0.2794 -0.1016)
			(end -0.2794 0.9906)
			(stroke
				(width 0.1)
				(type default)
			)
			(layer "F.Fab")
		)
		(fp_line
			(start 0.2794 0.9906)
			(end 0.2794 -0.1016)
			(stroke
				(width 0.1)
				(type default)
			)
			(layer "F.Fab")
		)
		(fp_line
			(start -0.2794 0.9906)
			(end 0.2794 0.9906)
			(stroke
				(width 0.1)
				(type default)
			)
			(layer "F.Fab")
		)
		(pad "1" smd rect
			(at 0 0 90)
			(size 0.508 0.508)
			(layers "F.Cu" "F.Mask" "F.Paste")
			(net "SVID_CLK1_CPU1_R")
		)
		(pad "2" smd rect
			(at 0 0.889 90)
			(size 0.508 0.508)
			(layers "F.Cu" "F.Mask" "F.Paste")
			(net "SVID_CLK_PVDDQ_KLM")
		)
		(zone
			(layer "F.Cu")
			(hatch none 0.5)
			(connect_pads
				(clearance 0)
			)
			(min_thickness 0.25)
			(keepout
				(tracks not_allowed)
				(vias allowed)
				(pads allowed)
				(copperpour not_allowed)
				(footprints allowed)
			)
			(placement
				(enabled no)
				(sheetname "")
			)
			(fill
				(thermal_gap 0.5)
				(thermal_bridge_width 0.5)
				(island_removal_mode 0)
			)
			(polygon
				(pts
					(xy -3.302 -128.3462) (xy -2.921 -128.3462) (xy -2.921 -128.8542) (xy -3.302 -128.8542)
				)
			)
		)
		(zone
			(layer "F.Cu")
			(hatch none 0.5)
			(connect_pads
				(clearance 0)
			)
			(min_thickness 0.25)
			(keepout
				(tracks allowed)
				(vias not_allowed)
				(pads allowed)
				(copperpour not_allowed)
				(footprints allowed)
			)
			(placement
				(enabled no)
				(sheetname "")
			)
			(fill
				(thermal_gap 0.5)
				(thermal_bridge_width 0.5)
				(island_removal_mode 0)
			)
			(polygon
				(pts
					(xy -3.302 -128.3462) (xy -2.921 -128.3462) (xy -2.921 -128.8542) (xy -3.302 -128.8542)
				)
			)
		)
	)
)
